(kicad_pcb
	(version 20260206)
	(generator "pcbnew")
	(generator_version "10.0")
	(general
		(thickness 1.6)
		(legacy_teardrops no)
	)
	(paper "A4")
	(title_block
		(title "03242023_DA0F0TMBIJ0_F0T_Motherboard_J_brd_V01_OCP.brd")
		(comment 1 "Grand Teton / footprints 4905-4912 of 6105")
	)
	(layers
		(0 "F.Cu" signal "TOP")
		(4 "In1.Cu" signal "GND")
		(6 "In2.Cu" signal "IN1")
		(8 "In3.Cu" signal "GND1")
		(10 "In4.Cu" signal "IN2")
		(12 "In5.Cu" signal "GND2")
		(14 "In6.Cu" signal "IN3")
		(16 "In7.Cu" signal "GND3")
		(18 "In8.Cu" signal "VCC")
		(20 "In9.Cu" signal "VCC1")
		(22 "In10.Cu" signal "GND4")
		(24 "In11.Cu" signal "IN4")
		(26 "In12.Cu" signal "GND5")
		(28 "In13.Cu" signal "IN5")
		(30 "In14.Cu" signal "GND6")
		(32 "In15.Cu" signal "IN6")
		(34 "In16.Cu" signal "GND7")
		(2 "B.Cu" signal "BOTTOM")
		(9 "F.Adhes" user "F.Adhesive")
		(11 "B.Adhes" user "B.Adhesive")
		(13 "F.Paste" user "Package Geometry/Pastemask Top")
		(15 "B.Paste" user "Package Geometry/Pastemask Bottom")
		(5 "F.SilkS" user "Ref Des/Silkscreen Top")
		(7 "B.SilkS" user "Ref Des/Silkscreen Bottom")
		(1 "F.Mask" user "Board Geometry/Soldermask Top")
		(3 "B.Mask" user "Board Geometry/Soldermask Bottom")
		(17 "Dwgs.User" user "User.Drawings")
		(19 "Cmts.User" user "User.Comments")
		(21 "Eco1.User" user "User.Eco1")
		(23 "Eco2.User" user "User.Eco2")
		(25 "Edge.Cuts" user "Board Geometry/Outline")
		(27 "Margin" user)
		(31 "F.CrtYd" user "Package Geometry/Place Bound Top")
		(29 "B.CrtYd" user "Package Geometry/Place Bound Bottom")
		(35 "F.Fab" user "Ref Des/Assembly Top")
		(33 "B.Fab" user "Ref Des/Assembly Bottom")
	)
	(footprint ""
		(layer "B.Cu")
		(at 446.727834 -179.862734 180)
		(property "Reference" "C1399"
			(at 0 0 0)
			(layer "B.SilkS")
			(hide yes)
			(effects
				(font
					(size 1.27 1.27)
				)
				(justify mirror)
			)
		)
		(property "Value" ""
			(at 0 0 0)
			(layer "B.Fab")
			(effects
				(font
					(size 1.27 1.27)
				)
				(justify mirror)
			)
		)
		(duplicate_pad_numbers_are_jumpers no)
		(fp_line
			(start 1.524 0.762)
			(end 1.524 -0.762)
			(stroke
				(width 0.1524)
				(type default)
			)
			(layer "B.SilkS")
		)
		(fp_line
			(start 1.524 -0.762)
			(end -1.524 -0.762)
			(stroke
				(width 0.1524)
				(type default)
			)
			(layer "B.SilkS")
		)
		(fp_line
			(start -1.524 0.762)
			(end 1.524 0.762)
			(stroke
				(width 0.1524)
				(type default)
			)
			(layer "B.SilkS")
		)
		(fp_line
			(start -1.524 -0.762)
			(end -1.524 0.762)
			(stroke
				(width 0.1524)
				(type default)
			)
			(layer "B.SilkS")
		)
		(fp_line
			(start 1.1049 0.724916)
			(end -1.1049 0.724916)
			(stroke
				(width 0.1)
				(type default)
			)
			(layer "B.Fab")
		)
		(fp_line
			(start 1.1049 -0.724916)
			(end 1.1049 0.724916)
			(stroke
				(width 0.1)
				(type default)
			)
			(layer "B.Fab")
		)
		(fp_line
			(start -1.1049 0.724916)
			(end -1.1049 -0.724916)
			(stroke
				(width 0.1)
				(type default)
			)
			(layer "B.Fab")
		)
		(fp_line
			(start -1.1049 -0.724916)
			(end 1.1049 -0.724916)
			(stroke
				(width 0.1)
				(type default)
			)
			(layer "B.Fab")
		)
		(pad "1" smd rect
			(at 0.889 0 180)
			(size 1.016 1.27)
			(layers "B.Cu" "B.Mask" "B.Paste")
			(net "PVNN_MAIN_CPU0")
		)
		(pad "2" smd rect
			(at -0.889 0 180)
			(size 1.016 1.27)
			(layers "B.Cu" "B.Mask" "B.Paste")
			(net "GND")
		)
	)
	(footprint ""
		(layer "B.Cu")
		(at 406.754838 -250.75515 90)
		(property "Reference" "C502"
			(at 0 0 90)
			(layer "B.SilkS")
			(hide yes)
			(effects
				(font
					(size 1.27 1.27)
				)
				(justify mirror)
			)
		)
		(property "Value" ""
			(at 0 0 90)
			(layer "B.Fab")
			(effects
				(font
					(size 1.27 1.27)
				)
				(justify mirror)
			)
		)
		(duplicate_pad_numbers_are_jumpers no)
		(fp_line
			(start 1.524 -0.762)
			(end -1.524 -0.762)
			(stroke
				(width 0.1524)
				(type default)
			)
			(layer "B.SilkS")
		)
		(fp_line
			(start -1.524 -0.762)
			(end -1.524 0.762)
			(stroke
				(width 0.1524)
				(type default)
			)
			(layer "B.SilkS")
		)
		(fp_line
			(start 1.524 0.762)
			(end 1.524 -0.762)
			(stroke
				(width 0.1524)
				(type default)
			)
			(layer "B.SilkS")
		)
		(fp_line
			(start -1.524 0.762)
			(end 1.524 0.762)
			(stroke
				(width 0.1524)
				(type default)
			)
			(layer "B.SilkS")
		)
		(fp_line
			(start 1.1049 -0.724916)
			(end 1.1049 0.724916)
			(stroke
				(width 0.1)
				(type default)
			)
			(layer "B.Fab")
		)
		(fp_line
			(start -1.1049 -0.724916)
			(end 1.1049 -0.724916)
			(stroke
				(width 0.1)
				(type default)
			)
			(layer "B.Fab")
		)
		(fp_line
			(start 1.1049 0.724916)
			(end -1.1049 0.724916)
			(stroke
				(width 0.1)
				(type default)
			)
			(layer "B.Fab")
		)
		(fp_line
			(start -1.1049 0.724916)
			(end -1.1049 -0.724916)
			(stroke
				(width 0.1)
				(type default)
			)
			(layer "B.Fab")
		)
		(pad "1" smd rect
			(at 0.889 0 90)
			(size 1.016 1.27)
			(layers "B.Cu" "B.Mask" "B.Paste")
			(net "PVCCFA_EHV_FIVRA_CPU0")
		)
		(pad "2" smd rect
			(at -0.889 0 90)
			(size 1.016 1.27)
			(layers "B.Cu" "B.Mask" "B.Paste")
			(net "GND")
		)
	)
	(footprint ""
		(layer "B.Cu")
		(at 362.6739 -212.049614 180)
		(property "Reference" "C503"
			(at 0 0 0)
			(layer "B.SilkS")
			(hide yes)
			(effects
				(font
					(size 1.27 1.27)
				)
				(justify mirror)
			)
		)
		(property "Value" ""
			(at 0 0 0)
			(layer "B.Fab")
			(effects
				(font
					(size 1.27 1.27)
				)
				(justify mirror)
			)
		)
		(duplicate_pad_numbers_are_jumpers no)
		(fp_line
			(start 1.524 0.762)
			(end 1.524 -0.762)
			(stroke
				(width 0.1524)
				(type default)
			)
			(layer "B.SilkS")
		)
		(fp_line
			(start 1.524 -0.762)
			(end -1.524 -0.762)
			(stroke
				(width 0.1524)
				(type default)
			)
			(layer "B.SilkS")
		)
		(fp_line
			(start -1.524 0.762)
			(end 1.524 0.762)
			(stroke
				(width 0.1524)
				(type default)
			)
			(layer "B.SilkS")
		)
		(fp_line
			(start -1.524 -0.762)
			(end -1.524 0.762)
			(stroke
				(width 0.1524)
				(type default)
			)
			(layer "B.SilkS")
		)
		(fp_line
			(start 1.1049 0.724916)
			(end -1.1049 0.724916)
			(stroke
				(width 0.1)
				(type default)
			)
			(layer "B.Fab")
		)
		(fp_line
			(start 1.1049 -0.724916)
			(end 1.1049 0.724916)
			(stroke
				(width 0.1)
				(type default)
			)
			(layer "B.Fab")
		)
		(fp_line
			(start -1.1049 0.724916)
			(end -1.1049 -0.724916)
			(stroke
				(width 0.1)
				(type default)
			)
			(layer "B.Fab")
		)
		(fp_line
			(start -1.1049 -0.724916)
			(end 1.1049 -0.724916)
			(stroke
				(width 0.1)
				(type default)
			)
			(layer "B.Fab")
		)
		(pad "1" smd rect
			(at 0.889 0 180)
			(size 1.016 1.27)
			(layers "B.Cu" "B.Mask" "B.Paste")
			(net "PVCCD_HV_CPU0")
		)
		(pad "2" smd rect
			(at -0.889 0 180)
			(size 1.016 1.27)
			(layers "B.Cu" "B.Mask" "B.Paste")
			(net "GND")
		)
	)
	(footprint ""
		(layer "B.Cu")
		(at 108.415074 -333.639922 90)
		(property "Reference" "PC570_P1_2"
			(at 0 0 90)
			(layer "B.SilkS")
			(hide yes)
			(effects
				(font
					(size 1.27 1.27)
				)
				(justify mirror)
			)
		)
		(property "Value" ""
			(at 0 0 90)
			(layer "B.Fab")
			(effects
				(font
					(size 1.27 1.27)
				)
				(justify mirror)
			)
		)
		(duplicate_pad_numbers_are_jumpers no)
		(fp_line
			(start 1.524 -0.762)
			(end -1.524 -0.762)
			(stroke
				(width 0.1524)
				(type default)
			)
			(layer "B.SilkS")
		)
		(fp_line
			(start -1.524 -0.762)
			(end -1.524 0.762)
			(stroke
				(width 0.1524)
				(type default)
			)
			(layer "B.SilkS")
		)
		(fp_line
			(start 1.524 0.762)
			(end 1.524 -0.762)
			(stroke
				(width 0.1524)
				(type default)
			)
			(layer "B.SilkS")
		)
		(fp_line
			(start -1.524 0.762)
			(end 1.524 0.762)
			(stroke
				(width 0.1524)
				(type default)
			)
			(layer "B.SilkS")
		)
		(fp_line
			(start 1.1049 -0.724916)
			(end 1.1049 0.724916)
			(stroke
				(width 0.1)
				(type default)
			)
			(layer "B.Fab")
		)
		(fp_line
			(start -1.1049 -0.724916)
			(end 1.1049 -0.724916)
			(stroke
				(width 0.1)
				(type default)
			)
			(layer "B.Fab")
		)
		(fp_line
			(start 1.1049 0.724916)
			(end -1.1049 0.724916)
			(stroke
				(width 0.1)
				(type default)
			)
			(layer "B.Fab")
		)
		(fp_line
			(start -1.1049 0.724916)
			(end -1.1049 -0.724916)
			(stroke
				(width 0.1)
				(type default)
			)
			(layer "B.Fab")
		)
		(pad "1" smd rect
			(at 0.889 0 90)
			(size 1.016 1.27)
			(layers "B.Cu" "B.Mask" "B.Paste")
			(net "SW_P12V_PVCCIN_CPU1_FLT")
		)
		(pad "2" smd rect
			(at -0.889 0 90)
			(size 1.016 1.27)
			(layers "B.Cu" "B.Mask" "B.Paste")
			(net "GND")
		)
	)
	(footprint ""
		(layer "B.Cu")
		(at 118.097554 -262.34898 180)
		(property "Reference" "C1388"
			(at 0 0 0)
			(layer "B.SilkS")
			(hide yes)
			(effects
				(font
					(size 1.27 1.27)
				)
				(justify mirror)
			)
		)
		(property "Value" ""
			(at 0 0 0)
			(layer "B.Fab")
			(effects
				(font
					(size 1.27 1.27)
				)
				(justify mirror)
			)
		)
		(duplicate_pad_numbers_are_jumpers no)
		(fp_line
			(start 1.524 0.762)
			(end 1.524 -0.762)
			(stroke
				(width 0.1524)
				(type default)
			)
			(layer "B.SilkS")
		)
		(fp_line
			(start 1.524 -0.762)
			(end -1.524 -0.762)
			(stroke
				(width 0.1524)
				(type default)
			)
			(layer "B.SilkS")
		)
		(fp_line
			(start -1.524 0.762)
			(end 1.524 0.762)
			(stroke
				(width 0.1524)
				(type default)
			)
			(layer "B.SilkS")
		)
		(fp_line
			(start -1.524 -0.762)
			(end -1.524 0.762)
			(stroke
				(width 0.1524)
				(type default)
			)
			(layer "B.SilkS")
		)
		(fp_line
			(start 1.1049 0.724916)
			(end -1.1049 0.724916)
			(stroke
				(width 0.1)
				(type default)
			)
			(layer "B.Fab")
		)
		(fp_line
			(start 1.1049 -0.724916)
			(end 1.1049 0.724916)
			(stroke
				(width 0.1)
				(type default)
			)
			(layer "B.Fab")
		)
		(fp_line
			(start -1.1049 0.724916)
			(end -1.1049 -0.724916)
			(stroke
				(width 0.1)
				(type default)
			)
			(layer "B.Fab")
		)
		(fp_line
			(start -1.1049 -0.724916)
			(end 1.1049 -0.724916)
			(stroke
				(width 0.1)
				(type default)
			)
			(layer "B.Fab")
		)
		(pad "1" smd rect
			(at 0.889 0 180)
			(size 1.016 1.27)
			(layers "B.Cu" "B.Mask" "B.Paste")
			(net "PVPP_HBM_CPU1")
		)
		(pad "2" smd rect
			(at -0.889 0 180)
			(size 1.016 1.27)
			(layers "B.Cu" "B.Mask" "B.Paste")
			(net "GND")
		)
	)
	(footprint ""
		(layer "B.Cu")
		(at 99.419918 -404.486618 -90)
		(property "Reference" "C2073"
			(at 0 0 90)
			(layer "B.SilkS")
			(hide yes)
			(effects
				(font
					(size 1.27 1.27)
				)
				(justify mirror)
			)
		)
		(property "Value" ""
			(at 0 0 90)
			(layer "B.Fab")
			(effects
				(font
					(size 1.27 1.27)
				)
				(justify mirror)
			)
		)
		(duplicate_pad_numbers_are_jumpers no)
		(fp_line
			(start -0.299974 0.150114)
			(end 0.299974 0.150114)
			(stroke
				(width 0.1)
				(type default)
			)
			(layer "B.Fab")
		)
		(fp_line
			(start 0.299974 0.150114)
			(end 0.299974 -0.150114)
			(stroke
				(width 0.1)
				(type default)
			)
			(layer "B.Fab")
		)
		(fp_line
			(start -0.299974 -0.150114)
			(end -0.299974 0.150114)
			(stroke
				(width 0.1)
				(type default)
			)
			(layer "B.Fab")
		)
		(fp_line
			(start 0.299974 -0.150114)
			(end -0.299974 -0.150114)
			(stroke
				(width 0.1)
				(type default)
			)
			(layer "B.Fab")
		)
		(pad "1" smd rect
			(at 0.2667 0 90)
			(size 0.3048 0.381)
			(layers "B.Cu" "B.Mask" "B.Paste")
			(net "P3E_PCH_NVS_TX_DP<1>")
		)
		(pad "2" smd rect
			(at -0.2667 0 90)
			(size 0.3048 0.381)
			(layers "B.Cu" "B.Mask" "B.Paste")
			(net "P3E_PCH_NVS_TX_C_DP<1>")
		)
		(zone
			(layer "In16.Cu")
			(hatch none 0.5)
			(connect_pads
				(clearance 0)
			)
			(min_thickness 0.25)
			(keepout
				(tracks not_allowed)
				(vias allowed)
				(pads allowed)
				(copperpour not_allowed)
				(footprints allowed)
			)
			(placement
				(enabled no)
				(sheetname "")
			)
			(fill
				(thermal_gap 0.5)
				(thermal_bridge_width 0.5)
				(island_removal_mode 0)
			)
			(polygon
				(pts
					(arc
						(start 99.178618 -404.626318)
						(mid 99.200936 -404.572436)
						(end 99.254818 -404.550118)
					)
					(arc
						(start 99.585018 -404.550118)
						(mid 99.6389 -404.572436)
						(end 99.661218 -404.626318)
					)
					(arc
						(start 99.661218 -404.880318)
						(mid 99.6389 -404.9342)
						(end 99.585018 -404.956518)
					)
					(arc
						(start 99.254818 -404.956518)
						(mid 99.200936 -404.9342)
						(end 99.178618 -404.880318)
					)
				)
			)
		)
		(zone
			(layer "In16.Cu")
			(hatch none 0.5)
			(connect_pads
				(clearance 0)
			)
			(min_thickness 0.25)
			(keepout
				(tracks not_allowed)
				(vias allowed)
				(pads allowed)
				(copperpour not_allowed)
				(footprints allowed)
			)
			(placement
				(enabled no)
				(sheetname "")
			)
			(fill
				(thermal_gap 0.5)
				(thermal_bridge_width 0.5)
				(island_removal_mode 0)
			)
			(polygon
				(pts
					(arc
						(start 99.178618 -404.092918)
						(mid 99.200936 -404.039036)
						(end 99.254818 -404.016718)
					)
					(arc
						(start 99.585018 -404.016718)
						(mid 99.6389 -404.039036)
						(end 99.661218 -404.092918)
					)
					(arc
						(start 99.661218 -404.346918)
						(mid 99.6389 -404.4008)
						(end 99.585018 -404.423118)
					)
					(arc
						(start 99.254818 -404.423118)
						(mid 99.200936 -404.4008)
						(end 99.178618 -404.346918)
					)
				)
			)
		)
	)
	(footprint ""
		(layer "B.Cu")
		(at 57.479946 -321.554856 -90)
		(property "Reference" "C51"
			(at 0 0 90)
			(layer "B.SilkS")
			(hide yes)
			(effects
				(font
					(size 1.27 1.27)
				)
				(justify mirror)
			)
		)
		(property "Value" ""
			(at 0 0 90)
			(layer "B.Fab")
			(effects
				(font
					(size 1.27 1.27)
				)
				(justify mirror)
			)
		)
		(duplicate_pad_numbers_are_jumpers no)
		(fp_line
			(start -1.524 0.762)
			(end 1.524 0.762)
			(stroke
				(width 0.1524)
				(type default)
			)
			(layer "B.SilkS")
		)
		(fp_line
			(start 1.524 0.762)
			(end 1.524 -0.762)
			(stroke
				(width 0.1524)
				(type default)
			)
			(layer "B.SilkS")
		)
		(fp_line
			(start -1.524 -0.762)
			(end -1.524 0.762)
			(stroke
				(width 0.1524)
				(type default)
			)
			(layer "B.SilkS")
		)
		(fp_line
			(start 1.524 -0.762)
			(end -1.524 -0.762)
			(stroke
				(width 0.1524)
				(type default)
			)
			(layer "B.SilkS")
		)
		(fp_line
			(start -1.1049 0.724916)
			(end -1.1049 -0.724916)
			(stroke
				(width 0.1)
				(type default)
			)
			(layer "B.Fab")
		)
		(fp_line
			(start 1.1049 0.724916)
			(end -1.1049 0.724916)
			(stroke
				(width 0.1)
				(type default)
			)
			(layer "B.Fab")
		)
		(fp_line
			(start -1.1049 -0.724916)
			(end 1.1049 -0.724916)
			(stroke
				(width 0.1)
				(type default)
			)
			(layer "B.Fab")
		)
		(fp_line
			(start 1.1049 -0.724916)
			(end 1.1049 0.724916)
			(stroke
				(width 0.1)
				(type default)
			)
			(layer "B.Fab")
		)
		(pad "1" smd rect
			(at 0.889 0 270)
			(size 1.016 1.27)
			(layers "B.Cu" "B.Mask" "B.Paste")
			(net "P12V_S3_AUX_CPU1_NVDIMM")
		)
		(pad "2" smd rect
			(at -0.889 0 270)
			(size 1.016 1.27)
			(layers "B.Cu" "B.Mask" "B.Paste")
			(net "GND")
		)
	)
	(footprint ""
		(layer "B.Cu")
		(at 29.586682 -164.167058)
		(property "Reference" "PR1315"
			(at 0 0 0)
			(layer "B.SilkS")
			(hide yes)
			(effects
				(font
					(size 1.27 1.27)
				)
				(justify mirror)
			)
		)
		(property "Value" ""
			(at 0 0 0)
			(layer "B.Fab")
			(effects
				(font
					(size 1.27 1.27)
				)
				(justify mirror)
			)
		)
		(duplicate_pad_numbers_are_jumpers no)
		(fp_line
			(start -0.7874 -0.4064)
			(end -0.7874 0.4064)
			(stroke
				(width 0.1524)
				(type default)
			)
			(layer "B.SilkS")
		)
		(fp_line
			(start -0.7874 0.4064)
			(end 0.7874 0.4064)
			(stroke
				(width 0.1524)
				(type default)
			)
			(layer "B.SilkS")
		)
		(fp_line
			(start 0.7874 -0.4064)
			(end -0.7874 -0.4064)
			(stroke
				(width 0.1524)
				(type default)
			)
			(layer "B.SilkS")
		)
		(fp_line
			(start 0.7874 0.4064)
			(end 0.7874 -0.4064)
			(stroke
				(width 0.1524)
				(type default)
			)
			(layer "B.SilkS")
		)
		(fp_line
			(start -0.67945 -0.3048)
			(end -0.67945 0.3048)
			(stroke
				(width 0.1)
				(type default)
			)
			(layer "B.Fab")
		)
		(fp_line
			(start -0.67945 0.3048)
			(end -0.120396 0.3048)
			(stroke
				(width 0.1)
				(type default)
			)
			(layer "B.Fab")
		)
		(fp_line
			(start -0.12065 -0.3048)
			(end -0.67945 -0.3048)
			(stroke
				(width 0.1)
				(type default)
			)
			(layer "B.Fab")
		)
		(fp_line
			(start -0.12065 -0.2794)
			(end -0.12065 -0.3048)
			(stroke
				(width 0.1)
				(type default)
			)
			(layer "B.Fab")
		)
		(fp_line
			(start -0.120396 0.2794)
			(end 0.12065 0.2794)
			(stroke
				(width 0.1)
				(type default)
			)
			(layer "B.Fab")
		)
		(fp_line
			(start -0.120396 0.3048)
			(end -0.120396 0.2794)
			(stroke
				(width 0.1)
				(type default)
			)
			(layer "B.Fab")
		)
		(fp_line
			(start 0.12065 -0.305054)
			(end 0.12065 -0.2794)
			(stroke
				(width 0.1)
				(type default)
			)
			(layer "B.Fab")
		)
		(fp_line
			(start 0.12065 -0.2794)
			(end -0.12065 -0.2794)
			(stroke
				(width 0.1)
				(type default)
			)
			(layer "B.Fab")
		)
		(fp_line
			(start 0.12065 0.2794)
			(end 0.12065 0.3048)
			(stroke
				(width 0.1)
				(type default)
			)
			(layer "B.Fab")
		)
		(fp_line
			(start 0.12065 0.3048)
			(end 0.67945 0.3048)
			(stroke
				(width 0.1)
				(type default)
			)
			(layer "B.Fab")
		)
		(fp_line
			(start 0.67945 -0.305054)
			(end 0.12065 -0.305054)
			(stroke
				(width 0.1)
				(type default)
			)
			(layer "B.Fab")
		)
		(fp_line
			(start 0.67945 0.3048)
			(end 0.67945 -0.305054)
			(stroke
				(width 0.1)
				(type default)
			)
			(layer "B.Fab")
		)
		(pad "1" smd circle
			(at 0.40005 0 180)
			(size 0 0)
			(layers "B.Cu" "B.Mask" "B.Paste")
			(net "PVCCD_HV_CPU1_ISYS_R")
		)
		(pad "2" smd circle
			(at -0.40005 0 180)
			(size 0 0)
			(layers "B.Cu" "B.Mask" "B.Paste")
			(net "GND")
		)
	)
)
